# BASEBOARD_FAB2 (Tioga Pass) — schematic netlist excerpt (pin names and nets, part order shuffled) for the footprints in the layout excerpt that follows; sources: Cadence DE-HDL packaged netlist, KiCad conversion of Wiwynn_Tioga_Pass_MB.brd

R6P15  RES  42.2 1.0% EMPTY  pkg 0402  page 103 : A = CLK_100M_CPU0_BCLK0_DN ; B = GND

Q1L3  NPN  MMBT3904 IC  pkg SM  page 168
  B  = FM_DB_UART_SEL4_N
  E  = GND
  C  = FM_DB_PRESENT

R8F23  RES  2.21K 1% CHIP  pkg 0402  page 157 : A = P3V3_STBY ; B = IRQ_MEZZ_LAN_ALERT_N

(kicad_pcb
	(version 20260206)
	(generator "pcbnew")
	(generator_version "10.0")
	(general
		(thickness 1.6)
		(legacy_teardrops no)
	)
	(paper "A4")
	(title_block
		(title "Wiwynn_Tioga_Pass_MB.brd")
		(comment 1 "Tioga Pass / footprints 4622-4624 of 4770")
	)
	(layers
		(0 "F.Cu" signal "TOP")
		(4 "In1.Cu" signal "L2GND")
		(6 "In2.Cu" signal "L3")
		(8 "In3.Cu" signal "L4GND")
		(10 "In4.Cu" signal "L5")
		(12 "In5.Cu" signal "L6GND")
		(14 "In6.Cu" signal "L7VCC")
		(16 "In7.Cu" signal "L8VCC")
		(18 "In8.Cu" signal "L9GND")
		(20 "In9.Cu" signal "L10")
		(22 "In10.Cu" signal "L11GND")
		(24 "In11.Cu" signal "L12")
		(26 "In12.Cu" signal "L13GND")
		(2 "B.Cu" signal "BOTTOM")
		(9 "F.Adhes" user "F.Adhesive")
		(11 "B.Adhes" user "B.Adhesive")
		(13 "F.Paste" user "Package Geometry/Pastemask Top")
		(15 "B.Paste" user "Package Geometry/Pastemask Bottom")
		(5 "F.SilkS" user "Ref Des/Silkscreen Top")
		(7 "B.SilkS" user "Ref Des/Silkscreen Bottom")
		(1 "F.Mask" user "Board Geometry/Soldermask Top")
		(3 "B.Mask" user "Board Geometry/Soldermask Bottom")
		(17 "Dwgs.User" user "User.Drawings")
		(19 "Cmts.User" user "User.Comments")
		(21 "Eco1.User" user "User.Eco1")
		(23 "Eco2.User" user "User.Eco2")
		(25 "Edge.Cuts" user "Board Geometry/Outline")
		(27 "Margin" user)
		(31 "F.CrtYd" user "Package Geometry/Place Bound Top")
		(29 "B.CrtYd" user "Package Geometry/Place Bound Bottom")
		(35 "F.Fab" user "Ref Des/Assembly Top")
		(33 "B.Fab" user "Ref Des/Assembly Bottom")
	)
	(footprint ""
		(layer "B.Cu")
		(at 176.149 -77.597 -90)
		(property "Reference" "R6P15"
			(at 0 0 90)
			(layer "B.SilkS")
			(hide yes)
			(effects
				(font
					(size 1.27 1.27)
				)
				(justify mirror)
			)
		)
		(property "Value" ""
			(at 0 0 90)
			(layer "B.Fab")
			(effects
				(font
					(size 1.27 1.27)
				)
				(justify mirror)
			)
		)
		(duplicate_pad_numbers_are_jumpers no)
		(fp_poly
			(pts
				(xy 0.2794 -0.1016) (xy -0.2794 -0.1016) (xy -0.2794 0.9906) (xy 0.2794 0.9906)
			)
			(stroke
				(width 0)
				(type default)
			)
			(fill no)
			(layer "B.CrtYd")
		)
		(fp_line
			(start -0.2794 0.9906)
			(end -0.2794 -0.1016)
			(stroke
				(width 0.1)
				(type default)
			)
			(layer "B.Fab")
		)
		(fp_line
			(start 0.2794 0.9906)
			(end -0.2794 0.9906)
			(stroke
				(width 0.1)
				(type default)
			)
			(layer "B.Fab")
		)
		(fp_line
			(start -0.2794 -0.1016)
			(end 0.2794 -0.1016)
			(stroke
				(width 0.1)
				(type default)
			)
			(layer "B.Fab")
		)
		(fp_line
			(start 0.2794 -0.1016)
			(end 0.2794 0.9906)
			(stroke
				(width 0.1)
				(type default)
			)
			(layer "B.Fab")
		)
		(pad "1" smd rect
			(at 0 0 90)
			(size 0.508 0.508)
			(layers "B.Cu" "B.Mask" "B.Paste")
			(net "CLK_100M_CPU0_BCLK0_DN")
		)
		(pad "2" smd rect
			(at 0 0.889 90)
			(size 0.508 0.508)
			(layers "B.Cu" "B.Mask" "B.Paste")
			(net "GND")
		)
		(zone
			(layer "B.Cu")
			(hatch none 0.5)
			(connect_pads
				(clearance 0)
			)
			(min_thickness 0.25)
			(keepout
				(tracks not_allowed)
				(vias allowed)
				(pads allowed)
				(copperpour not_allowed)
				(footprints allowed)
			)
			(placement
				(enabled no)
				(sheetname "")
			)
			(fill
				(thermal_gap 0.5)
				(thermal_bridge_width 0.5)
				(island_removal_mode 0)
			)
			(polygon
				(pts
					(xy 175.514 -77.343) (xy 175.514 -77.851) (xy 175.895 -77.851) (xy 175.895 -77.343)
				)
			)
		)
		(zone
			(layer "B.Cu")
			(hatch none 0.5)
			(connect_pads
				(clearance 0)
			)
			(min_thickness 0.25)
			(keepout
				(tracks allowed)
				(vias not_allowed)
				(pads allowed)
				(copperpour not_allowed)
				(footprints allowed)
			)
			(placement
				(enabled no)
				(sheetname "")
			)
			(fill
				(thermal_gap 0.5)
				(thermal_bridge_width 0.5)
				(island_removal_mode 0)
			)
			(polygon
				(pts
					(xy 175.895 -77.343) (xy 175.895 -77.851) (xy 175.514 -77.851) (xy 175.514 -77.343)
				)
			)
		)
	)
	(footprint ""
		(layer "B.Cu")
		(at 401.472146 -41.360852 90)
		(property "Reference" "R8F23"
			(at 0 0 90)
			(layer "B.SilkS")
			(hide yes)
			(effects
				(font
					(size 1.27 1.27)
				)
				(justify mirror)
			)
		)
		(property "Value" ""
			(at 0 0 90)
			(layer "B.Fab")
			(effects
				(font
					(size 1.27 1.27)
				)
				(justify mirror)
			)
		)
		(duplicate_pad_numbers_are_jumpers no)
		(fp_poly
			(pts
				(xy 0.2794 -0.1016) (xy -0.2794 -0.1016) (xy -0.2794 0.9906) (xy 0.2794 0.9906)
			)
			(stroke
				(width 0)
				(type default)
			)
			(fill no)
			(layer "B.CrtYd")
		)
		(fp_line
			(start 0.2794 -0.1016)
			(end 0.2794 0.9906)
			(stroke
				(width 0.1)
				(type default)
			)
			(layer "B.Fab")
		)
		(fp_line
			(start -0.2794 -0.1016)
			(end 0.2794 -0.1016)
			(stroke
				(width 0.1)
				(type default)
			)
			(layer "B.Fab")
		)
		(fp_line
			(start 0.2794 0.9906)
			(end -0.2794 0.9906)
			(stroke
				(width 0.1)
				(type default)
			)
			(layer "B.Fab")
		)
		(fp_line
			(start -0.2794 0.9906)
			(end -0.2794 -0.1016)
			(stroke
				(width 0.1)
				(type default)
			)
			(layer "B.Fab")
		)
		(pad "1" smd rect
			(at 0 0 270)
			(size 0.508 0.508)
			(layers "B.Cu" "B.Mask" "B.Paste")
			(net "P3V3_STBY")
		)
		(pad "2" smd rect
			(at 0 0.889 270)
			(size 0.508 0.508)
			(layers "B.Cu" "B.Mask" "B.Paste")
			(net "IRQ_MEZZ_LAN_ALERT_N")
		)
		(zone
			(layer "B.Cu")
			(hatch none 0.5)
			(connect_pads
				(clearance 0)
			)
			(min_thickness 0.25)
			(keepout
				(tracks allowed)
				(vias not_allowed)
				(pads allowed)
				(copperpour not_allowed)
				(footprints allowed)
			)
			(placement
				(enabled no)
				(sheetname "")
			)
			(fill
				(thermal_gap 0.5)
				(thermal_bridge_width 0.5)
				(island_removal_mode 0)
			)
			(polygon
				(pts
					(xy 401.726146 -41.614852) (xy 401.726146 -41.106852) (xy 402.107146 -41.106852) (xy 402.107146 -41.614852)
				)
			)
		)
		(zone
			(layer "B.Cu")
			(hatch none 0.5)
			(connect_pads
				(clearance 0)
			)
			(min_thickness 0.25)
			(keepout
				(tracks not_allowed)
				(vias allowed)
				(pads allowed)
				(copperpour not_allowed)
				(footprints allowed)
			)
			(placement
				(enabled no)
				(sheetname "")
			)
			(fill
				(thermal_gap 0.5)
				(thermal_bridge_width 0.5)
				(island_removal_mode 0)
			)
			(polygon
				(pts
					(xy 402.107146 -41.614852) (xy 402.107146 -41.106852) (xy 401.726146 -41.106852) (xy 401.726146 -41.614852)
				)
			)
		)
	)
	(footprint ""
		(layer "B.Cu")
		(at 483.6795 -139.5095 180)
		(property "Reference" "Q1L3"
			(at -2.48285 0.50546 90)
			(unlocked yes)
			(layer "B.SilkS")
			(effects
				(font
					(size 0.7874 0.5842)
					(thickness 0.1524)
				)
				(justify left mirror)
			)
		)
		(property "Value" ""
			(at 0 0 0)
			(layer "B.Fab")
			(effects
				(font
					(size 1.27 1.27)
				)
				(justify mirror)
			)
		)
		(duplicate_pad_numbers_are_jumpers no)
		(fp_line
			(start -0.381 0.635)
			(end -0.381 1.27)
			(stroke
				(width 0.1524)
				(type default)
			)
			(layer "B.SilkS")
		)
		(fp_line
			(start -0.9525 2.4765)
			(end -1.778 2.4765)
			(stroke
				(width 0.1524)
				(type default)
			)
			(layer "B.SilkS")
		)
		(fp_line
			(start -0.9525 -0.5715)
			(end -1.778 -0.5715)
			(stroke
				(width 0.1524)
				(type default)
			)
			(layer "B.SilkS")
		)
		(fp_line
			(start -1.778 2.4765)
			(end -1.778 1.5875)
			(stroke
				(width 0.1524)
				(type default)
			)
			(layer "B.SilkS")
		)
		(fp_line
			(start -1.778 -0.5715)
			(end -1.778 0.3175)
			(stroke
				(width 0.1524)
				(type default)
			)
			(layer "B.SilkS")
		)
		(fp_circle
			(center 0.9525 -0.9271)
			(end 0.8255 -0.9271)
			(stroke
				(width 0.254)
				(type default)
			)
			(fill no)
			(layer "B.SilkS")
		)
		(fp_poly
			(pts
				(xy -1.778 2.4765) (xy -0.381 2.4765) (xy -0.381 -0.5715) (xy -1.778 -0.5715)
			)
			(stroke
				(width 0)
				(type default)
			)
			(fill no)
			(layer "B.CrtYd")
		)
		(fp_line
			(start -0.381 2.4765)
			(end -1.778 2.4765)
			(stroke
				(width 0.1)
				(type default)
			)
			(layer "B.Fab")
		)
		(fp_line
			(start -0.381 -0.5715)
			(end -0.381 2.4765)
			(stroke
				(width 0.1)
				(type default)
			)
			(layer "B.Fab")
		)
		(fp_line
			(start -1.778 2.4765)
			(end -1.778 -0.5715)
			(stroke
				(width 0.1)
				(type default)
			)
			(layer "B.Fab")
		)
		(fp_line
			(start -1.778 -0.5715)
			(end -0.381 -0.5715)
			(stroke
				(width 0.1)
				(type default)
			)
			(layer "B.Fab")
		)
		(fp_circle
			(center 0.9525 -0.9271)
			(end 0.8255 -0.9271)
			(stroke
				(width 0.254)
				(type default)
			)
			(fill no)
			(layer "B.Fab")
		)
		(pad "1" smd rect
			(at 0 0)
			(size 1.143 0.508)
			(layers "B.Cu" "B.Mask" "B.Paste")
			(net "FM_DB_UART_SEL4_N")
		)
		(pad "2" smd rect
			(at 0 1.905)
			(size 1.143 0.508)
			(layers "B.Cu" "B.Mask" "B.Paste")
			(net "GND")
		)
		(pad "3" smd rect
			(at -2.159 0.9525)
			(size 1.143 0.508)
			(layers "B.Cu" "B.Mask" "B.Paste")
			(net "FM_DB_PRESENT")
		)
	)
)
